# TIMECARD (Time Appliance Project (Time Card)) — schematic netlist excerpt (pin names and nets, part order shuffled) for the footprints in the layout excerpt that follows; sources: Cadence DE-HDL packaged netlist, KiCad conversion of R4006-B0001-02_R01.brd

C272  CAPACITOR  0.1UF 25V 10%  pkg SMC_0402R_H022  page 22 : \1\ = XP5R0V ; \2\ = SG
C72  CAPACITOR  10UF 25V 20%  pkg SMC_0805R_H057  page 22 : \1\ = XP5R0V_VCC_ANT ; \2\ = SG

(kicad_pcb
	(version 20260206)
	(generator "pcbnew")
	(generator_version "10.0")
	(general
		(thickness 1.6)
		(legacy_teardrops no)
	)
	(paper "A4")
	(title_block
		(title "timecard-production-celestica-r4006 — R4006-B0001-02_R01.brd")
		(comment 1 "Time Appliance Project (Time Card) / footprints 499-500 of 1113")
	)
	(layers
		(0 "F.Cu" signal "TOP")
		(4 "In1.Cu" signal "L02_GND1")
		(6 "In2.Cu" signal "L03_SIG1")
		(8 "In3.Cu" signal "L04_GND2")
		(10 "In4.Cu" signal "L05_VCC1")
		(12 "In5.Cu" signal "L06_VCC2")
		(14 "In6.Cu" signal "L07_GND3")
		(16 "In7.Cu" signal "L08_SIG2")
		(18 "In8.Cu" signal "L09_GND4")
		(2 "B.Cu" signal "BOTTOM")
		(9 "F.Adhes" user "F.Adhesive")
		(11 "B.Adhes" user "B.Adhesive")
		(13 "F.Paste" user "Package Geometry/Pastemask Top")
		(15 "B.Paste" user "Package Geometry/Pastemask Bottom")
		(5 "F.SilkS" user "Ref Des/Silkscreen Top")
		(7 "B.SilkS" user "Ref Des/Silkscreen Bottom")
		(1 "F.Mask" user "Board Geometry/Soldermask Top")
		(3 "B.Mask" user "Board Geometry/Soldermask Bottom")
		(17 "Dwgs.User" user "User.Drawings")
		(19 "Cmts.User" user "User.Comments")
		(21 "Eco1.User" user "User.Eco1")
		(23 "Eco2.User" user "User.Eco2")
		(25 "Edge.Cuts" user "Board Geometry/Outline")
		(27 "Margin" user)
		(31 "F.CrtYd" user "Package Geometry/Place Bound Top")
		(29 "B.CrtYd" user "Package Geometry/Place Bound Bottom")
		(35 "F.Fab" user "Ref Des/Assembly Top")
		(33 "B.Fab" user "Ref Des/Assembly Bottom")
	)
	(footprint ""
		(layer "F.Cu")
		(at 128.27 -98.298 -90)
		(property "Reference" "C72"
			(at -2.921 -1.43637 90)
			(unlocked yes)
			(layer "F.SilkS")
			(effects
				(font
					(size 0.7874 0.5842)
					(thickness 0.1524)
				)
			)
		)
		(property "Value" "VAL*"
			(at 0.0762 3.134106 270)
			(unlocked yes)
			(layer "F.Fab")
			(hide yes)
			(effects
				(font
					(size 0.7874 0.5842)
					(thickness 0.1524)
				)
			)
		)
		(property "Device Type" "CAPACITOR-G107-0F106-EM,10UF,2A"
			(at 0.0508 2.194306 270)
			(unlocked yes)
			(layer "F.Fab")
			(hide yes)
			(effects
				(font
					(size 0.7874 0.5842)
					(thickness 0.1524)
				)
			)
		)
		(property "User Part Number" "PARTNUM*"
			(at 0.1016 5.013706 270)
			(unlocked yes)
			(layer "Cmts.User")
			(hide yes)
			(effects
				(font
					(size 0.7874 0.5842)
					(thickness 0.1524)
				)
			)
		)
		(property "Tolerance" "TOL*"
			(at 0.0762 4.048506 270)
			(unlocked yes)
			(layer "Cmts.User")
			(hide yes)
			(effects
				(font
					(size 0.7874 0.5842)
					(thickness 0.1524)
				)
			)
		)
		(duplicate_pad_numbers_are_jumpers no)
		(fp_line
			(start -1.5748 0.9398)
			(end 1.5748 0.9398)
			(stroke
				(width 0.1)
				(type default)
			)
			(layer "F.SilkS")
		)
		(fp_line
			(start 1.5748 0.9398)
			(end 1.5748 -0.9398)
			(stroke
				(width 0.1)
				(type default)
			)
			(layer "F.SilkS")
		)
		(fp_line
			(start -1.5748 -0.9398)
			(end -1.5748 0.9398)
			(stroke
				(width 0.1)
				(type default)
			)
			(layer "F.SilkS")
		)
		(fp_line
			(start 1.5748 -0.9398)
			(end -1.5748 -0.9398)
			(stroke
				(width 0.1)
				(type default)
			)
			(layer "F.SilkS")
		)
		(fp_rect
			(start 1.5748 0.9398)
			(end -1.5748 -0.9398)
			(stroke
				(width 0)
				(type default)
			)
			(fill no)
			(layer "F.CrtYd")
		)
		(fp_line
			(start -1.016 0.635)
			(end 1.016 0.635)
			(stroke
				(width 0.1)
				(type default)
			)
			(layer "F.Fab")
		)
		(fp_line
			(start 1.016 0.635)
			(end 1.016 -0.635)
			(stroke
				(width 0.1)
				(type default)
			)
			(layer "F.Fab")
		)
		(fp_line
			(start -1.016 -0.635)
			(end -1.016 0.635)
			(stroke
				(width 0.1)
				(type default)
			)
			(layer "F.Fab")
		)
		(fp_line
			(start 1.016 -0.635)
			(end -1.016 -0.635)
			(stroke
				(width 0.1)
				(type default)
			)
			(layer "F.Fab")
		)
		(pad "1" smd rect
			(at -0.8382 0 270)
			(size 0.9652 1.3716)
			(layers "F.Cu" "F.Mask" "F.Paste")
			(net "XP5R0V_VCC_ANT")
		)
		(pad "2" smd rect
			(at 0.8382 0 270)
			(size 0.9652 1.3716)
			(layers "F.Cu" "F.Mask" "F.Paste")
			(net "SG")
		)
		(zone
			(layer "F.Cu")
			(hatch none 0.5)
			(connect_pads
				(clearance 0)
			)
			(min_thickness 0.25)
			(keepout
				(tracks allowed)
				(vias not_allowed)
				(pads allowed)
				(copperpour not_allowed)
				(footprints allowed)
			)
			(placement
				(enabled no)
				(sheetname "")
			)
			(fill
				(thermal_gap 0.5)
				(thermal_bridge_width 0.5)
				(island_removal_mode 0)
			)
			(polygon
				(pts
					(xy 127.635 -98.0694) (xy 128.905 -98.0694) (xy 128.905 -98.5266) (xy 127.635 -98.5266)
				)
			)
		)
	)
	(footprint ""
		(layer "F.Cu")
		(at 129.794 -95.885 180)
		(property "Reference" "C272"
			(at -0.127 -1.69037 0)
			(unlocked yes)
			(layer "F.SilkS")
			(effects
				(font
					(size 0.7874 0.5842)
					(thickness 0.1524)
				)
			)
		)
		(property "Value" "VAL*"
			(at 0.0762 2.067306 180)
			(unlocked yes)
			(layer "F.Fab")
			(hide yes)
			(effects
				(font
					(size 0.7874 0.5842)
					(thickness 0.1524)
				)
			)
		)
		(property "Device Type" "CAPACITOR-G105-0B104-EK,0.1UF,A"
			(at 0.0508 1.127506 180)
			(unlocked yes)
			(layer "F.Fab")
			(hide yes)
			(effects
				(font
					(size 0.7874 0.5842)
					(thickness 0.1524)
				)
			)
		)
		(property "User Part Number" "PARTNUM*"
			(at 0.1016 4.023106 180)
			(unlocked yes)
			(layer "Cmts.User")
			(hide yes)
			(effects
				(font
					(size 0.7874 0.5842)
					(thickness 0.1524)
				)
			)
		)
		(property "Tolerance" "TOL*"
			(at 0.0762 3.032506 180)
			(unlocked yes)
			(layer "Cmts.User")
			(hide yes)
			(effects
				(font
					(size 0.7874 0.5842)
					(thickness 0.1524)
				)
			)
		)
		(duplicate_pad_numbers_are_jumpers no)
		(fp_line
			(start 1.143 0.5588)
			(end 1.143 -0.5588)
			(stroke
				(width 0.1)
				(type default)
			)
			(layer "F.SilkS")
		)
		(fp_line
			(start 1.143 -0.5588)
			(end -1.143 -0.5588)
			(stroke
				(width 0.1)
				(type default)
			)
			(layer "F.SilkS")
		)
		(fp_line
			(start -1.143 0.5588)
			(end 1.143 0.5588)
			(stroke
				(width 0.1)
				(type default)
			)
			(layer "F.SilkS")
		)
		(fp_line
			(start -1.143 -0.5588)
			(end -1.143 0.5588)
			(stroke
				(width 0.1)
				(type default)
			)
			(layer "F.SilkS")
		)
		(fp_rect
			(start -1.143 0.5588)
			(end 1.143 -0.5588)
			(stroke
				(width 0)
				(type default)
			)
			(fill no)
			(layer "F.CrtYd")
		)
		(fp_line
			(start 0.508 0.3048)
			(end 0.508 -0.3048)
			(stroke
				(width 0.1)
				(type default)
			)
			(layer "F.Fab")
		)
		(fp_line
			(start 0.508 -0.3048)
			(end -0.508 -0.3048)
			(stroke
				(width 0.1)
				(type default)
			)
			(layer "F.Fab")
		)
		(fp_line
			(start -0.508 0.3048)
			(end 0.508 0.3048)
			(stroke
				(width 0.1)
				(type default)
			)
			(layer "F.Fab")
		)
		(fp_line
			(start -0.508 -0.3048)
			(end -0.508 0.3048)
			(stroke
				(width 0.1)
				(type default)
			)
			(layer "F.Fab")
		)
		(pad "1" smd rect
			(at -0.5334 0 180)
			(size 0.7112 0.6096)
			(layers "F.Cu" "F.Mask" "F.Paste")
			(net "XP5R0V")
		)
		(pad "2" smd rect
			(at 0.5334 0 180)
			(size 0.7112 0.6096)
			(layers "F.Cu" "F.Mask" "F.Paste")
			(net "SG")
		)
		(zone
			(layer "F.Cu")
			(hatch none 0.5)
			(connect_pads
				(clearance 0)
			)
			(min_thickness 0.25)
			(keepout
				(tracks allowed)
				(vias not_allowed)
				(pads allowed)
				(copperpour not_allowed)
				(footprints allowed)
			)
			(placement
				(enabled no)
				(sheetname "")
			)
			(fill
				(thermal_gap 0.5)
				(thermal_bridge_width 0.5)
				(island_removal_mode 0)
			)
			(polygon
				(pts
					(xy 129.8702 -96.1898) (xy 129.7178 -96.1898) (xy 129.7178 -95.5802) (xy 129.8702 -95.5802)
				)
			)
		)
	)
)
